# BASEBOARD_FAB2 (Tioga Pass) — schematic netlist excerpt (pin names and nets, part order shuffled) for the footprints in the layout excerpt that follows; sources: Cadence DE-HDL packaged netlist, KiCad conversion of Wiwynn_Tioga_Pass_MB.brd

R6P1  RES  42.2 1.0% EMPTY  pkg 0402  page 103 : A = CLK_100M_CPU0_RC_REFCLK0_DP ; B = GND
R8E23  RES  4.75K 1% CHIP  pkg 0402  page 142 : A = PU_TRI_STATE_EN ; B = P3V3_STBY
C3T10  CAP  1.0UF 16V 10% X6S  pkg 0402  page 231 : A = VR_FET_SW_P12V_STBY_PVPP_ABC ; B = GND

(kicad_pcb
	(version 20260206)
	(generator "pcbnew")
	(generator_version "10.0")
	(general
		(thickness 1.6)
		(legacy_teardrops no)
	)
	(paper "A4")
	(title_block
		(title "Wiwynn_Tioga_Pass_MB.brd")
		(comment 1 "Tioga Pass / footprints 4229-4231 of 4770")
	)
	(layers
		(0 "F.Cu" signal "TOP")
		(4 "In1.Cu" signal "L2GND")
		(6 "In2.Cu" signal "L3")
		(8 "In3.Cu" signal "L4GND")
		(10 "In4.Cu" signal "L5")
		(12 "In5.Cu" signal "L6GND")
		(14 "In6.Cu" signal "L7VCC")
		(16 "In7.Cu" signal "L8VCC")
		(18 "In8.Cu" signal "L9GND")
		(20 "In9.Cu" signal "L10")
		(22 "In10.Cu" signal "L11GND")
		(24 "In11.Cu" signal "L12")
		(26 "In12.Cu" signal "L13GND")
		(2 "B.Cu" signal "BOTTOM")
		(9 "F.Adhes" user "F.Adhesive")
		(11 "B.Adhes" user "B.Adhesive")
		(13 "F.Paste" user "Package Geometry/Pastemask Top")
		(15 "B.Paste" user "Package Geometry/Pastemask Bottom")
		(5 "F.SilkS" user "Ref Des/Silkscreen Top")
		(7 "B.SilkS" user "Ref Des/Silkscreen Bottom")
		(1 "F.Mask" user "Board Geometry/Soldermask Top")
		(3 "B.Mask" user "Board Geometry/Soldermask Bottom")
		(17 "Dwgs.User" user "User.Drawings")
		(19 "Cmts.User" user "User.Comments")
		(21 "Eco1.User" user "User.Eco1")
		(23 "Eco2.User" user "User.Eco2")
		(25 "Edge.Cuts" user "Board Geometry/Outline")
		(27 "Margin" user)
		(31 "F.CrtYd" user "Package Geometry/Place Bound Top")
		(29 "B.CrtYd" user "Package Geometry/Place Bound Bottom")
		(35 "F.Fab" user "Ref Des/Assembly Top")
		(33 "B.Fab" user "Ref Des/Assembly Bottom")
	)
	(footprint ""
		(layer "B.Cu")
		(at 349.631 -27.9654 180)
		(property "Reference" "C3T10"
			(at 0 0 0)
			(layer "B.SilkS")
			(hide yes)
			(effects
				(font
					(size 1.27 1.27)
				)
				(justify mirror)
			)
		)
		(property "Value" ""
			(at 0 0 0)
			(layer "B.Fab")
			(effects
				(font
					(size 1.27 1.27)
				)
				(justify mirror)
			)
		)
		(duplicate_pad_numbers_are_jumpers no)
		(fp_poly
			(pts
				(xy -0.3048 -0.1016) (xy -0.3048 0.9906) (xy 0.3048 0.9906) (xy 0.3048 -0.1016)
			)
			(stroke
				(width 0)
				(type default)
			)
			(fill no)
			(layer "B.CrtYd")
		)
		(fp_line
			(start 0.3048 0.9906)
			(end -0.3048 0.9906)
			(stroke
				(width 0.1)
				(type default)
			)
			(layer "B.Fab")
		)
		(fp_line
			(start 0.3048 -0.1016)
			(end 0.3048 0.9906)
			(stroke
				(width 0.1)
				(type default)
			)
			(layer "B.Fab")
		)
		(fp_line
			(start -0.3048 0.9906)
			(end -0.3048 -0.1016)
			(stroke
				(width 0.1)
				(type default)
			)
			(layer "B.Fab")
		)
		(fp_line
			(start -0.3048 -0.1016)
			(end 0.3048 -0.1016)
			(stroke
				(width 0.1)
				(type default)
			)
			(layer "B.Fab")
		)
		(pad "1" smd rect
			(at 0 0)
			(size 0.508 0.508)
			(layers "B.Cu" "B.Mask" "B.Paste")
			(net "VR_FET_SW_P12V_STBY_PVPP_ABC")
		)
		(pad "2" smd rect
			(at 0 0.889)
			(size 0.508 0.508)
			(layers "B.Cu" "B.Mask" "B.Paste")
			(net "GND")
		)
		(zone
			(layer "B.Cu")
			(hatch none 0.5)
			(connect_pads
				(clearance 0)
			)
			(min_thickness 0.25)
			(keepout
				(tracks not_allowed)
				(vias allowed)
				(pads allowed)
				(copperpour not_allowed)
				(footprints allowed)
			)
			(placement
				(enabled no)
				(sheetname "")
			)
			(fill
				(thermal_gap 0.5)
				(thermal_bridge_width 0.5)
				(island_removal_mode 0)
			)
			(polygon
				(pts
					(xy 349.377 -28.6004) (xy 349.885 -28.6004) (xy 349.885 -28.2194) (xy 349.377 -28.2194)
				)
			)
		)
		(zone
			(layer "B.Cu")
			(hatch none 0.5)
			(connect_pads
				(clearance 0)
			)
			(min_thickness 0.25)
			(keepout
				(tracks allowed)
				(vias not_allowed)
				(pads allowed)
				(copperpour not_allowed)
				(footprints allowed)
			)
			(placement
				(enabled no)
				(sheetname "")
			)
			(fill
				(thermal_gap 0.5)
				(thermal_bridge_width 0.5)
				(island_removal_mode 0)
			)
			(polygon
				(pts
					(xy 349.377 -28.2194) (xy 349.885 -28.2194) (xy 349.885 -28.6004) (xy 349.377 -28.6004)
				)
			)
		)
	)
	(footprint ""
		(layer "B.Cu")
		(at 173.736 -87.757)
		(property "Reference" "R6P1"
			(at 0 0 0)
			(layer "B.SilkS")
			(hide yes)
			(effects
				(font
					(size 1.27 1.27)
				)
				(justify mirror)
			)
		)
		(property "Value" ""
			(at 0 0 0)
			(layer "B.Fab")
			(effects
				(font
					(size 1.27 1.27)
				)
				(justify mirror)
			)
		)
		(duplicate_pad_numbers_are_jumpers no)
		(fp_poly
			(pts
				(xy 0.2794 -0.1016) (xy -0.2794 -0.1016) (xy -0.2794 0.9906) (xy 0.2794 0.9906)
			)
			(stroke
				(width 0)
				(type default)
			)
			(fill no)
			(layer "B.CrtYd")
		)
		(fp_line
			(start -0.2794 -0.1016)
			(end 0.2794 -0.1016)
			(stroke
				(width 0.1)
				(type default)
			)
			(layer "B.Fab")
		)
		(fp_line
			(start -0.2794 0.9906)
			(end -0.2794 -0.1016)
			(stroke
				(width 0.1)
				(type default)
			)
			(layer "B.Fab")
		)
		(fp_line
			(start 0.2794 -0.1016)
			(end 0.2794 0.9906)
			(stroke
				(width 0.1)
				(type default)
			)
			(layer "B.Fab")
		)
		(fp_line
			(start 0.2794 0.9906)
			(end -0.2794 0.9906)
			(stroke
				(width 0.1)
				(type default)
			)
			(layer "B.Fab")
		)
		(pad "1" smd rect
			(at 0 0 180)
			(size 0.508 0.508)
			(layers "B.Cu" "B.Mask" "B.Paste")
			(net "CLK_100M_CPU0_RC_REFCLK0_DP")
		)
		(pad "2" smd rect
			(at 0 0.889 180)
			(size 0.508 0.508)
			(layers "B.Cu" "B.Mask" "B.Paste")
			(net "GND")
		)
		(zone
			(layer "B.Cu")
			(hatch none 0.5)
			(connect_pads
				(clearance 0)
			)
			(min_thickness 0.25)
			(keepout
				(tracks allowed)
				(vias not_allowed)
				(pads allowed)
				(copperpour not_allowed)
				(footprints allowed)
			)
			(placement
				(enabled no)
				(sheetname "")
			)
			(fill
				(thermal_gap 0.5)
				(thermal_bridge_width 0.5)
				(island_removal_mode 0)
			)
			(polygon
				(pts
					(xy 173.99 -87.503) (xy 173.482 -87.503) (xy 173.482 -87.122) (xy 173.99 -87.122)
				)
			)
		)
		(zone
			(layer "B.Cu")
			(hatch none 0.5)
			(connect_pads
				(clearance 0)
			)
			(min_thickness 0.25)
			(keepout
				(tracks not_allowed)
				(vias allowed)
				(pads allowed)
				(copperpour not_allowed)
				(footprints allowed)
			)
			(placement
				(enabled no)
				(sheetname "")
			)
			(fill
				(thermal_gap 0.5)
				(thermal_bridge_width 0.5)
				(island_removal_mode 0)
			)
			(polygon
				(pts
					(xy 173.99 -87.122) (xy 173.482 -87.122) (xy 173.482 -87.503) (xy 173.99 -87.503)
				)
			)
		)
	)
	(footprint ""
		(layer "B.Cu")
		(at 480.037902 -55.990998)
		(property "Reference" "R8E23"
			(at 0 0 0)
			(layer "B.SilkS")
			(hide yes)
			(effects
				(font
					(size 1.27 1.27)
				)
				(justify mirror)
			)
		)
		(property "Value" ""
			(at 0 0 0)
			(layer "B.Fab")
			(effects
				(font
					(size 1.27 1.27)
				)
				(justify mirror)
			)
		)
		(duplicate_pad_numbers_are_jumpers no)
		(fp_poly
			(pts
				(xy 0.2794 -0.1016) (xy -0.2794 -0.1016) (xy -0.2794 0.9906) (xy 0.2794 0.9906)
			)
			(stroke
				(width 0)
				(type default)
			)
			(fill no)
			(layer "B.CrtYd")
		)
		(fp_line
			(start -0.2794 -0.1016)
			(end 0.2794 -0.1016)
			(stroke
				(width 0.1)
				(type default)
			)
			(layer "B.Fab")
		)
		(fp_line
			(start -0.2794 0.9906)
			(end -0.2794 -0.1016)
			(stroke
				(width 0.1)
				(type default)
			)
			(layer "B.Fab")
		)
		(fp_line
			(start 0.2794 -0.1016)
			(end 0.2794 0.9906)
			(stroke
				(width 0.1)
				(type default)
			)
			(layer "B.Fab")
		)
		(fp_line
			(start 0.2794 0.9906)
			(end -0.2794 0.9906)
			(stroke
				(width 0.1)
				(type default)
			)
			(layer "B.Fab")
		)
		(pad "1" smd rect
			(at 0 0 180)
			(size 0.508 0.508)
			(layers "B.Cu" "B.Mask" "B.Paste")
			(net "PU_TRI_STATE_EN")
		)
		(pad "2" smd rect
			(at 0 0.889 180)
			(size 0.508 0.508)
			(layers "B.Cu" "B.Mask" "B.Paste")
			(net "P3V3_STBY")
		)
		(zone
			(layer "B.Cu")
			(hatch none 0.5)
			(connect_pads
				(clearance 0)
			)
			(min_thickness 0.25)
			(keepout
				(tracks allowed)
				(vias not_allowed)
				(pads allowed)
				(copperpour not_allowed)
				(footprints allowed)
			)
			(placement
				(enabled no)
				(sheetname "")
			)
			(fill
				(thermal_gap 0.5)
				(thermal_bridge_width 0.5)
				(island_removal_mode 0)
			)
			(polygon
				(pts
					(xy 480.291902 -55.736998) (xy 479.783902 -55.736998) (xy 479.783902 -55.355998) (xy 480.291902 -55.355998)
				)
			)
		)
		(zone
			(layer "B.Cu")
			(hatch none 0.5)
			(connect_pads
				(clearance 0)
			)
			(min_thickness 0.25)
			(keepout
				(tracks not_allowed)
				(vias allowed)
				(pads allowed)
				(copperpour not_allowed)
				(footprints allowed)
			)
			(placement
				(enabled no)
				(sheetname "")
			)
			(fill
				(thermal_gap 0.5)
				(thermal_bridge_width 0.5)
				(island_removal_mode 0)
			)
			(polygon
				(pts
					(xy 480.291902 -55.355998) (xy 479.783902 -55.355998) (xy 479.783902 -55.736998) (xy 480.291902 -55.736998)
				)
			)
		)
	)
)
